# LED_BOM.xls — Sheet0 (bom)
| Description | Qty | Location |
| TIOGA PASS CHANNEL LED CARD SB (SMT) | 1 |  |
| HEAD ML 1R15P T1M-15-F-SV-L-P SMD | 1 | CN1 |
| CHIP RES 270 J 1/16W 0402 | 4 | R1 R3 R5 R7 |
| CHIP RES 0 J 1/16W 0402 | 4 | R13 R14 R15 R16 |
| CHIP RES 10K F 1/16W 0402 | 4 | R2 R4 R6 R8 |
| CHIP RES 1.2K F 1/10W0603(ROHS | 1 | PR1 |
| IC CMOS 74LVC1G07DCKR SC70-5 | 4 | U1 U2 U3 U4 |
| CHIP CAP C 0.1U 25V K0402 X5R | 1 | PC2 |
| CHIP CAP C 1U 6.3V K0402 X5R | 1 | PC1 |
| LED Y/G 26-21/G6C-BQ2S1LY/CT SMD | 4 | LED1 LED2 LED3 LED4 |
| DIODE ZEN MMPZ5228BPT SOD-323 | 1 | PD1 |
| XTOR MMBT3904W NPN SOT-323 | 1 | PQ1 |
| PCB 16368-SB LBC LED CARD 6L | 1 |  |
